(kicad_pcb
	(version 20260206)
	(generator "pcbnew")
	(generator_version "10.0")
	(general
		(thickness 1.6)
		(legacy_teardrops no)
	)
	(paper "A4")
	(title_block
		(title "timecard-production-celestica-r4006 — R4006-B0001-02_R01.brd")
		(comment 1 "Time Appliance Project (Time Card) / footprints 892-896 of 1113")
	)
	(layers
		(0 "F.Cu" signal "TOP")
		(4 "In1.Cu" signal "L02_GND1")
		(6 "In2.Cu" signal "L03_SIG1")
		(8 "In3.Cu" signal "L04_GND2")
		(10 "In4.Cu" signal "L05_VCC1")
		(12 "In5.Cu" signal "L06_VCC2")
		(14 "In6.Cu" signal "L07_GND3")
		(16 "In7.Cu" signal "L08_SIG2")
		(18 "In8.Cu" signal "L09_GND4")
		(2 "B.Cu" signal "BOTTOM")
		(9 "F.Adhes" user "F.Adhesive")
		(11 "B.Adhes" user "B.Adhesive")
		(13 "F.Paste" user "Package Geometry/Pastemask Top")
		(15 "B.Paste" user "Package Geometry/Pastemask Bottom")
		(5 "F.SilkS" user "Ref Des/Silkscreen Top")
		(7 "B.SilkS" user "Ref Des/Silkscreen Bottom")
		(1 "F.Mask" user "Board Geometry/Soldermask Top")
		(3 "B.Mask" user "Board Geometry/Soldermask Bottom")
		(17 "Dwgs.User" user "User.Drawings")
		(19 "Cmts.User" user "User.Comments")
		(21 "Eco1.User" user "User.Eco1")
		(23 "Eco2.User" user "User.Eco2")
		(25 "Edge.Cuts" user "Board Geometry/Outline")
		(27 "Margin" user)
		(31 "F.CrtYd" user "Package Geometry/Place Bound Top")
		(29 "B.CrtYd" user "Package Geometry/Place Bound Bottom")
		(35 "F.Fab" user "Ref Des/Assembly Top")
		(33 "B.Fab" user "Ref Des/Assembly Bottom")
	)
	(footprint ""
		(layer "B.Cu")
		(at 126.1364 -32.0802)
		(property "Reference" "C168"
			(at -0.127 2.07137 0)
			(unlocked yes)
			(layer "B.SilkS")
			(effects
				(font
					(size 0.7874 0.5842)
					(thickness 0.1524)
				)
				(justify mirror)
			)
		)
		(property "Value" "VAL*"
			(at -0.0762 3.134106 0)
			(unlocked yes)
			(layer "B.Fab")
			(hide yes)
			(effects
				(font
					(size 0.7874 0.5842)
					(thickness 0.1524)
				)
				(justify mirror)
			)
		)
		(property "Tolerance" "TOL*"
			(at -0.0762 4.048506 0)
			(unlocked yes)
			(layer "Cmts.User")
			(hide yes)
			(effects
				(font
					(size 0.7874 0.5842)
					(thickness 0.1524)
				)
				(justify mirror)
			)
		)
		(property "User Part Number" "PARTNUM*"
			(at -0.1016 5.013706 0)
			(unlocked yes)
			(layer "Cmts.User")
			(hide yes)
			(effects
				(font
					(size 0.7874 0.5842)
					(thickness 0.1524)
				)
				(justify mirror)
			)
		)
		(property "Device Type" "CAPACITOR-G107-0F226-CM,22UF,2A"
			(at -0.0508 2.194306 0)
			(unlocked yes)
			(layer "B.Fab")
			(hide yes)
			(effects
				(font
					(size 0.7874 0.5842)
					(thickness 0.1524)
				)
				(justify mirror)
			)
		)
		(duplicate_pad_numbers_are_jumpers no)
		(fp_line
			(start -1.5748 -0.9398)
			(end 1.5748 -0.9398)
			(stroke
				(width 0.1)
				(type default)
			)
			(layer "B.SilkS")
		)
		(fp_line
			(start -1.5748 0.9398)
			(end -1.5748 -0.9398)
			(stroke
				(width 0.1)
				(type default)
			)
			(layer "B.SilkS")
		)
		(fp_line
			(start 1.5748 -0.9398)
			(end 1.5748 0.9398)
			(stroke
				(width 0.1)
				(type default)
			)
			(layer "B.SilkS")
		)
		(fp_line
			(start 1.5748 0.9398)
			(end -1.5748 0.9398)
			(stroke
				(width 0.1)
				(type default)
			)
			(layer "B.SilkS")
		)
		(fp_rect
			(start -1.5748 -0.9398)
			(end 1.5748 0.9398)
			(stroke
				(width 0)
				(type default)
			)
			(fill no)
			(layer "B.CrtYd")
		)
		(fp_line
			(start -1.016 -0.635)
			(end 1.016 -0.635)
			(stroke
				(width 0.1)
				(type default)
			)
			(layer "B.Fab")
		)
		(fp_line
			(start -1.016 0.635)
			(end -1.016 -0.635)
			(stroke
				(width 0.1)
				(type default)
			)
			(layer "B.Fab")
		)
		(fp_line
			(start 1.016 -0.635)
			(end 1.016 0.635)
			(stroke
				(width 0.1)
				(type default)
			)
			(layer "B.Fab")
		)
		(fp_line
			(start 1.016 0.635)
			(end -1.016 0.635)
			(stroke
				(width 0.1)
				(type default)
			)
			(layer "B.Fab")
		)
		(pad "1" smd rect
			(at 0.8382 0 180)
			(size 0.9652 1.3716)
			(layers "B.Cu" "B.Mask" "B.Paste")
			(net "XP2R5V_FPGA")
		)
		(pad "2" smd rect
			(at -0.8382 0 180)
			(size 0.9652 1.3716)
			(layers "B.Cu" "B.Mask" "B.Paste")
			(net "SG")
		)
		(zone
			(layer "B.Cu")
			(hatch none 0.5)
			(connect_pads
				(clearance 0)
			)
			(min_thickness 0.25)
			(keepout
				(tracks allowed)
				(vias not_allowed)
				(pads allowed)
				(copperpour not_allowed)
				(footprints allowed)
			)
			(placement
				(enabled no)
				(sheetname "")
			)
			(fill
				(thermal_gap 0.5)
				(thermal_bridge_width 0.5)
				(island_removal_mode 0)
			)
			(polygon
				(pts
					(xy 125.9078 -32.7152) (xy 125.9078 -31.4452) (xy 126.365 -31.4452) (xy 126.365 -32.7152)
				)
			)
		)
	)
	(footprint ""
		(layer "B.Cu")
		(at 94.615 -43.688 180)
		(property "Reference" "R196"
			(at 3.556 0.08763 0)
			(unlocked yes)
			(layer "B.SilkS")
			(effects
				(font
					(size 0.7874 0.5842)
					(thickness 0.1524)
				)
				(justify mirror)
			)
		)
		(property "Value" "VAL*"
			(at -0.02032 2.13233 180)
			(unlocked yes)
			(layer "B.Fab")
			(hide yes)
			(effects
				(font
					(size 0.7874 0.5842)
					(thickness 0.1524)
				)
				(justify mirror)
			)
		)
		(property "Tolerance" "TOL*"
			(at -0.044704 3.05435 180)
			(unlocked yes)
			(layer "Cmts.User")
			(hide yes)
			(effects
				(font
					(size 0.7874 0.5842)
					(thickness 0.1524)
				)
				(justify mirror)
			)
		)
		(property "User Part Number" "PARTNUM*"
			(at -0.02032 4.024884 180)
			(unlocked yes)
			(layer "Cmts.User")
			(hide yes)
			(effects
				(font
					(size 0.7874 0.5842)
					(thickness 0.1524)
				)
				(justify mirror)
			)
		)
		(property "Device Type" "RESISTOR-G155-11000-01,100OHM,A"
			(at -0.008382 1.210564 180)
			(unlocked yes)
			(layer "B.Fab")
			(hide yes)
			(effects
				(font
					(size 0.7874 0.5842)
					(thickness 0.1524)
				)
				(justify mirror)
			)
		)
		(duplicate_pad_numbers_are_jumpers no)
		(fp_line
			(start 1.143 0.5588)
			(end -1.143 0.5588)
			(stroke
				(width 0.1)
				(type default)
			)
			(layer "B.SilkS")
		)
		(fp_line
			(start 1.143 -0.5588)
			(end 1.143 0.5588)
			(stroke
				(width 0.1)
				(type default)
			)
			(layer "B.SilkS")
		)
		(fp_line
			(start -1.143 0.5588)
			(end -1.143 -0.5588)
			(stroke
				(width 0.1)
				(type default)
			)
			(layer "B.SilkS")
		)
		(fp_line
			(start -1.143 -0.5588)
			(end 1.143 -0.5588)
			(stroke
				(width 0.1)
				(type default)
			)
			(layer "B.SilkS")
		)
		(fp_rect
			(start 1.143 -0.5588)
			(end -1.143 0.5588)
			(stroke
				(width 0)
				(type default)
			)
			(fill no)
			(layer "B.CrtYd")
		)
		(fp_line
			(start 0.508 0.3048)
			(end -0.508 0.3048)
			(stroke
				(width 0.1)
				(type default)
			)
			(layer "B.Fab")
		)
		(fp_line
			(start 0.508 -0.3048)
			(end 0.508 0.3048)
			(stroke
				(width 0.1)
				(type default)
			)
			(layer "B.Fab")
		)
		(fp_line
			(start -0.508 0.3048)
			(end -0.508 -0.3048)
			(stroke
				(width 0.1)
				(type default)
			)
			(layer "B.Fab")
		)
		(fp_line
			(start -0.508 -0.3048)
			(end 0.508 -0.3048)
			(stroke
				(width 0.1)
				(type default)
			)
			(layer "B.Fab")
		)
		(pad "1" smd rect
			(at 0.5334 0)
			(size 0.7112 0.6096)
			(layers "B.Cu" "B.Mask" "B.Paste")
			(net "FPGA_MGTAVTT")
		)
		(pad "2" smd rect
			(at -0.5334 0)
			(size 0.7112 0.6096)
			(layers "B.Cu" "B.Mask" "B.Paste")
			(net "FPGA_MGTRREF")
		)
		(zone
			(layer "B.Cu")
			(hatch none 0.5)
			(connect_pads
				(clearance 0)
			)
			(min_thickness 0.25)
			(keepout
				(tracks allowed)
				(vias not_allowed)
				(pads allowed)
				(copperpour not_allowed)
				(footprints allowed)
			)
			(placement
				(enabled no)
				(sheetname "")
			)
			(fill
				(thermal_gap 0.5)
				(thermal_bridge_width 0.5)
				(island_removal_mode 0)
			)
			(polygon
				(pts
					(xy 94.5388 -43.3832) (xy 94.6912 -43.3832) (xy 94.6912 -43.9928) (xy 94.5388 -43.9928)
				)
			)
		)
	)
	(footprint ""
		(layer "B.Cu")
		(at 70.866 -58.8518 90)
		(property "Reference" "C70"
			(at 2.6162 7.70763 270)
			(unlocked yes)
			(layer "B.SilkS")
			(effects
				(font
					(size 0.7874 0.5842)
					(thickness 0.1524)
				)
				(justify mirror)
			)
		)
		(property "Value" "VAL*"
			(at -0.0762 2.067306 90)
			(unlocked yes)
			(layer "B.Fab")
			(hide yes)
			(effects
				(font
					(size 0.7874 0.5842)
					(thickness 0.1524)
				)
				(justify mirror)
			)
		)
		(property "Tolerance" "TOL*"
			(at -0.0762 3.032506 90)
			(unlocked yes)
			(layer "Cmts.User")
			(hide yes)
			(effects
				(font
					(size 0.7874 0.5842)
					(thickness 0.1524)
				)
				(justify mirror)
			)
		)
		(property "User Part Number" "PARTNUM*"
			(at -0.1016 4.023106 90)
			(unlocked yes)
			(layer "Cmts.User")
			(hide yes)
			(effects
				(font
					(size 0.7874 0.5842)
					(thickness 0.1524)
				)
				(justify mirror)
			)
		)
		(property "Device Type" "CAPACITOR-G105-0B104-EK,0.1UF,A"
			(at -0.0508 1.127506 90)
			(unlocked yes)
			(layer "B.Fab")
			(hide yes)
			(effects
				(font
					(size 0.7874 0.5842)
					(thickness 0.1524)
				)
				(justify mirror)
			)
		)
		(duplicate_pad_numbers_are_jumpers no)
		(fp_line
			(start 1.143 -0.5588)
			(end 1.143 0.5588)
			(stroke
				(width 0.1)
				(type default)
			)
			(layer "B.SilkS")
		)
		(fp_line
			(start -1.143 -0.5588)
			(end 1.143 -0.5588)
			(stroke
				(width 0.1)
				(type default)
			)
			(layer "B.SilkS")
		)
		(fp_line
			(start 1.143 0.5588)
			(end -1.143 0.5588)
			(stroke
				(width 0.1)
				(type default)
			)
			(layer "B.SilkS")
		)
		(fp_line
			(start -1.143 0.5588)
			(end -1.143 -0.5588)
			(stroke
				(width 0.1)
				(type default)
			)
			(layer "B.SilkS")
		)
		(fp_rect
			(start -1.143 -0.5588)
			(end 1.143 0.5588)
			(stroke
				(width 0)
				(type default)
			)
			(fill no)
			(layer "B.CrtYd")
		)
		(fp_line
			(start 0.508 -0.3048)
			(end 0.508 0.3048)
			(stroke
				(width 0.1)
				(type default)
			)
			(layer "B.Fab")
		)
		(fp_line
			(start -0.508 -0.3048)
			(end 0.508 -0.3048)
			(stroke
				(width 0.1)
				(type default)
			)
			(layer "B.Fab")
		)
		(fp_line
			(start 0.508 0.3048)
			(end -0.508 0.3048)
			(stroke
				(width 0.1)
				(type default)
			)
			(layer "B.Fab")
		)
		(fp_line
			(start -0.508 0.3048)
			(end -0.508 -0.3048)
			(stroke
				(width 0.1)
				(type default)
			)
			(layer "B.Fab")
		)
		(pad "1" smd rect
			(at 0.5334 0 270)
			(size 0.7112 0.6096)
			(layers "B.Cu" "B.Mask" "B.Paste")
			(net "XP5R0V_MAC")
		)
		(pad "2" smd rect
			(at -0.5334 0 270)
			(size 0.7112 0.6096)
			(layers "B.Cu" "B.Mask" "B.Paste")
			(net "SG")
		)
		(zone
			(layer "B.Cu")
			(hatch none 0.5)
			(connect_pads
				(clearance 0)
			)
			(min_thickness 0.25)
			(keepout
				(tracks allowed)
				(vias not_allowed)
				(pads allowed)
				(copperpour not_allowed)
				(footprints allowed)
			)
			(placement
				(enabled no)
				(sheetname "")
			)
			(fill
				(thermal_gap 0.5)
				(thermal_bridge_width 0.5)
				(island_removal_mode 0)
			)
			(polygon
				(pts
					(xy 70.5612 -58.7756) (xy 71.1708 -58.7756) (xy 71.1708 -58.928) (xy 70.5612 -58.928)
				)
			)
		)
	)
	(footprint ""
		(layer "B.Cu")
		(at 89.9922 -102.4128 180)
		(property "Reference" "C286"
			(at -3.3528 -0.09017 0)
			(unlocked yes)
			(layer "B.SilkS")
			(effects
				(font
					(size 0.7874 0.5842)
					(thickness 0.1524)
				)
				(justify mirror)
			)
		)
		(property "Value" "VAL*"
			(at -0.0762 2.067306 180)
			(unlocked yes)
			(layer "B.Fab")
			(hide yes)
			(effects
				(font
					(size 0.7874 0.5842)
					(thickness 0.1524)
				)
				(justify mirror)
			)
		)
		(property "Tolerance" "TOL*"
			(at -0.0762 3.032506 180)
			(unlocked yes)
			(layer "Cmts.User")
			(hide yes)
			(effects
				(font
					(size 0.7874 0.5842)
					(thickness 0.1524)
				)
				(justify mirror)
			)
		)
		(property "User Part Number" "PARTNUM*"
			(at -0.1016 4.023106 180)
			(unlocked yes)
			(layer "Cmts.User")
			(hide yes)
			(effects
				(font
					(size 0.7874 0.5842)
					(thickness 0.1524)
				)
				(justify mirror)
			)
		)
		(property "Device Type" "CAPACITOR-G105-0B224-DK,0.22UFA"
			(at -0.0508 1.127506 180)
			(unlocked yes)
			(layer "B.Fab")
			(hide yes)
			(effects
				(font
					(size 0.7874 0.5842)
					(thickness 0.1524)
				)
				(justify mirror)
			)
		)
		(duplicate_pad_numbers_are_jumpers no)
		(fp_line
			(start 1.143 0.5588)
			(end -1.143 0.5588)
			(stroke
				(width 0.1)
				(type default)
			)
			(layer "B.SilkS")
		)
		(fp_line
			(start 1.143 -0.5588)
			(end 1.143 0.5588)
			(stroke
				(width 0.1)
				(type default)
			)
			(layer "B.SilkS")
		)
		(fp_line
			(start -1.143 0.5588)
			(end -1.143 -0.5588)
			(stroke
				(width 0.1)
				(type default)
			)
			(layer "B.SilkS")
		)
		(fp_line
			(start -1.143 -0.5588)
			(end 1.143 -0.5588)
			(stroke
				(width 0.1)
				(type default)
			)
			(layer "B.SilkS")
		)
		(fp_rect
			(start 1.143 -0.5588)
			(end -1.143 0.5588)
			(stroke
				(width 0)
				(type default)
			)
			(fill no)
			(layer "B.CrtYd")
		)
		(fp_line
			(start 0.508 0.3048)
			(end -0.508 0.3048)
			(stroke
				(width 0.1)
				(type default)
			)
			(layer "B.Fab")
		)
		(fp_line
			(start 0.508 -0.3048)
			(end 0.508 0.3048)
			(stroke
				(width 0.1)
				(type default)
			)
			(layer "B.Fab")
		)
		(fp_line
			(start -0.508 0.3048)
			(end -0.508 -0.3048)
			(stroke
				(width 0.1)
				(type default)
			)
			(layer "B.Fab")
		)
		(fp_line
			(start -0.508 -0.3048)
			(end 0.508 -0.3048)
			(stroke
				(width 0.1)
				(type default)
			)
			(layer "B.Fab")
		)
		(pad "1" smd rect
			(at 0.5334 0)
			(size 0.7112 0.6096)
			(layers "B.Cu" "B.Mask" "B.Paste")
			(net "XP3R3V_EN")
		)
		(pad "2" smd rect
			(at -0.5334 0)
			(size 0.7112 0.6096)
			(layers "B.Cu" "B.Mask" "B.Paste")
			(net "SG")
		)
		(zone
			(layer "B.Cu")
			(hatch none 0.5)
			(connect_pads
				(clearance 0)
			)
			(min_thickness 0.25)
			(keepout
				(tracks allowed)
				(vias not_allowed)
				(pads allowed)
				(copperpour not_allowed)
				(footprints allowed)
			)
			(placement
				(enabled no)
				(sheetname "")
			)
			(fill
				(thermal_gap 0.5)
				(thermal_bridge_width 0.5)
				(island_removal_mode 0)
			)
			(polygon
				(pts
					(xy 89.916 -102.108) (xy 90.0684 -102.108) (xy 90.0684 -102.7176) (xy 89.916 -102.7176)
				)
			)
		)
		(zone
			(layer "B.Cu")
			(hatch none 0.5)
			(connect_pads
				(clearance 0)
			)
			(min_thickness 0.25)
			(keepout
				(tracks not_allowed)
				(vias allowed)
				(pads allowed)
				(copperpour not_allowed)
				(footprints allowed)
			)
			(placement
				(enabled no)
				(sheetname "")
			)
			(fill
				(thermal_gap 0.5)
				(thermal_bridge_width 0.5)
				(island_removal_mode 0)
			)
			(polygon
				(pts
					(xy 89.916 -102.108) (xy 90.0684 -102.108) (xy 90.0684 -102.7176) (xy 89.916 -102.7176)
				)
			)
		)
	)
	(footprint ""
		(layer "B.Cu")
		(at 153.035 -104.394 90)
		(property "Reference" "R119"
			(at -1.27 1.10363 270)
			(unlocked yes)
			(layer "B.SilkS")
			(effects
				(font
					(size 0.7874 0.5842)
					(thickness 0.1524)
				)
				(justify mirror)
			)
		)
		(property "Value" "VAL*"
			(at -0.02032 2.13233 90)
			(unlocked yes)
			(layer "B.Fab")
			(hide yes)
			(effects
				(font
					(size 0.7874 0.5842)
					(thickness 0.1524)
				)
				(justify mirror)
			)
		)
		(property "Tolerance" "TOL*"
			(at -0.044704 3.05435 90)
			(unlocked yes)
			(layer "Cmts.User")
			(hide yes)
			(effects
				(font
					(size 0.7874 0.5842)
					(thickness 0.1524)
				)
				(justify mirror)
			)
		)
		(property "User Part Number" "PARTNUM*"
			(at -0.02032 4.024884 90)
			(unlocked yes)
			(layer "Cmts.User")
			(hide yes)
			(effects
				(font
					(size 0.7874 0.5842)
					(thickness 0.1524)
				)
				(justify mirror)
			)
		)
		(property "Device Type" "RESISTOR-G155-13300-01,330OHM,A"
			(at -0.008382 1.210564 90)
			(unlocked yes)
			(layer "B.Fab")
			(hide yes)
			(effects
				(font
					(size 0.7874 0.5842)
					(thickness 0.1524)
				)
				(justify mirror)
			)
		)
		(duplicate_pad_numbers_are_jumpers no)
		(fp_line
			(start 1.143 -0.5588)
			(end 1.143 0.5588)
			(stroke
				(width 0.1)
				(type default)
			)
			(layer "B.SilkS")
		)
		(fp_line
			(start -1.143 -0.5588)
			(end 1.143 -0.5588)
			(stroke
				(width 0.1)
				(type default)
			)
			(layer "B.SilkS")
		)
		(fp_line
			(start 1.143 0.5588)
			(end -1.143 0.5588)
			(stroke
				(width 0.1)
				(type default)
			)
			(layer "B.SilkS")
		)
		(fp_line
			(start -1.143 0.5588)
			(end -1.143 -0.5588)
			(stroke
				(width 0.1)
				(type default)
			)
			(layer "B.SilkS")
		)
		(fp_poly
			(pts
				(xy 1.143 0.5588) (xy -1.143 0.5588) (xy -1.143 -0.5588) (xy 1.143 -0.5588)
			)
			(stroke
				(width 0)
				(type default)
			)
			(fill no)
			(layer "B.CrtYd")
		)
		(fp_line
			(start 0.508 -0.3048)
			(end 0.508 0.3048)
			(stroke
				(width 0.1)
				(type default)
			)
			(layer "B.Fab")
		)
		(fp_line
			(start -0.508 -0.3048)
			(end 0.508 -0.3048)
			(stroke
				(width 0.1)
				(type default)
			)
			(layer "B.Fab")
		)
		(fp_line
			(start 0.508 0.3048)
			(end -0.508 0.3048)
			(stroke
				(width 0.1)
				(type default)
			)
			(layer "B.Fab")
		)
		(fp_line
			(start -0.508 0.3048)
			(end -0.508 -0.3048)
			(stroke
				(width 0.1)
				(type default)
			)
			(layer "B.Fab")
		)
		(pad "1" smd rect
			(at 0.5334 0 270)
			(size 0.7112 0.6096)
			(layers "B.Cu" "B.Mask" "B.Paste")
			(net "UNNAMED_14_OPTICAL_I194_A")
		)
		(pad "2" smd rect
			(at -0.5334 0 270)
			(size 0.7112 0.6096)
			(layers "B.Cu" "B.Mask" "B.Paste")
			(net "XP3R3V_AUX_PCIE")
		)
		(zone
			(layer "B.Cu")
			(hatch none 0.5)
			(connect_pads
				(clearance 0)
			)
			(min_thickness 0.25)
			(keepout
				(tracks allowed)
				(vias not_allowed)
				(pads allowed)
				(copperpour not_allowed)
				(footprints allowed)
			)
			(placement
				(enabled no)
				(sheetname "")
			)
			(fill
				(thermal_gap 0.5)
				(thermal_bridge_width 0.5)
				(island_removal_mode 0)
			)
			(polygon
				(pts
					(xy 153.3398 -104.4702) (xy 152.7302 -104.4702) (xy 152.7302 -104.3178) (xy 153.3398 -104.3178)
				)
			)
		)
		(zone
			(layer "B.Cu")
			(hatch none 0.5)
			(connect_pads
				(clearance 0)
			)
			(min_thickness 0.25)
			(keepout
				(tracks not_allowed)
				(vias allowed)
				(pads allowed)
				(copperpour not_allowed)
				(footprints allowed)
			)
			(placement
				(enabled no)
				(sheetname "")
			)
			(fill
				(thermal_gap 0.5)
				(thermal_bridge_width 0.5)
				(island_removal_mode 0)
			)
			(polygon
				(pts
					(xy 153.3398 -104.4702) (xy 152.7302 -104.4702) (xy 152.7302 -104.3178) (xy 153.3398 -104.3178)
				)
			)
		)
	)
)
